# TIMECARD (Time Appliance Project (Time Card)) — schematic netlist excerpt (pin names and nets, part order shuffled) for the footprints in the layout excerpt that follows; sources: Cadence DE-HDL packaged netlist, KiCad conversion of R4006-B0001-02_R01.brd

SP41  SOLDER_PREFORM  pkg 0201_SOLDER_PREFORM_4MIL  page 34 : \1\ = NC ; \2\ = NC
L18  FERRITEBEAD  600OHM 25%  pkg SMC_0603R_H037  page 19 : \1\ = XP1R8V_FPGA ; \2\ = XP1R8V_ICP10100
R401  RESISTOR  100OHM 1%  pkg SMC_0402R_H016  page 26 : \1\ = FPGA_OUT_SMA4_LED_GREEN_N ; \2\ = UNNAMED_14_LED4PV14_I268_4

(kicad_pcb
	(version 20260206)
	(generator "pcbnew")
	(generator_version "10.0")
	(general
		(thickness 1.6)
		(legacy_teardrops no)
	)
	(paper "A4")
	(title_block
		(title "timecard-production-celestica-r4006 — R4006-B0001-02_R01.brd")
		(comment 1 "Time Appliance Project (Time Card) / footprints 168-170 of 1113")
	)
	(layers
		(0 "F.Cu" signal "TOP")
		(4 "In1.Cu" signal "L02_GND1")
		(6 "In2.Cu" signal "L03_SIG1")
		(8 "In3.Cu" signal "L04_GND2")
		(10 "In4.Cu" signal "L05_VCC1")
		(12 "In5.Cu" signal "L06_VCC2")
		(14 "In6.Cu" signal "L07_GND3")
		(16 "In7.Cu" signal "L08_SIG2")
		(18 "In8.Cu" signal "L09_GND4")
		(2 "B.Cu" signal "BOTTOM")
		(9 "F.Adhes" user "F.Adhesive")
		(11 "B.Adhes" user "B.Adhesive")
		(13 "F.Paste" user "Package Geometry/Pastemask Top")
		(15 "B.Paste" user "Package Geometry/Pastemask Bottom")
		(5 "F.SilkS" user "Ref Des/Silkscreen Top")
		(7 "B.SilkS" user "Ref Des/Silkscreen Bottom")
		(1 "F.Mask" user "Board Geometry/Soldermask Top")
		(3 "B.Mask" user "Board Geometry/Soldermask Bottom")
		(17 "Dwgs.User" user "User.Drawings")
		(19 "Cmts.User" user "User.Comments")
		(21 "Eco1.User" user "User.Eco1")
		(23 "Eco2.User" user "User.Eco2")
		(25 "Edge.Cuts" user "Board Geometry/Outline")
		(27 "Margin" user)
		(31 "F.CrtYd" user "Package Geometry/Place Bound Top")
		(29 "B.CrtYd" user "Package Geometry/Place Bound Bottom")
		(35 "F.Fab" user "Ref Des/Assembly Top")
		(33 "B.Fab" user "Ref Des/Assembly Bottom")
	)
	(footprint ""
		(layer "F.Cu")
		(at 19.468338 -50.165 180)
		(property "Reference" "R401"
			(at -2.883662 0.21463 0)
			(unlocked yes)
			(layer "F.SilkS")
			(effects
				(font
					(size 0.7874 0.5842)
					(thickness 0.1524)
				)
			)
		)
		(property "Value" "VAL*"
			(at 0.02032 2.13233 180)
			(unlocked yes)
			(layer "F.Fab")
			(hide yes)
			(effects
				(font
					(size 0.7874 0.5842)
					(thickness 0.1524)
				)
			)
		)
		(property "Device Type" "RESISTOR-G155-11000-01,100OHM,A"
			(at 0.008382 1.210564 180)
			(unlocked yes)
			(layer "F.Fab")
			(hide yes)
			(effects
				(font
					(size 0.7874 0.5842)
					(thickness 0.1524)
				)
			)
		)
		(property "User Part Number" "PARTNUM*"
			(at 0.02032 4.024884 180)
			(unlocked yes)
			(layer "Cmts.User")
			(hide yes)
			(effects
				(font
					(size 0.7874 0.5842)
					(thickness 0.1524)
				)
			)
		)
		(property "Tolerance" "TOL*"
			(at 0.044704 3.05435 180)
			(unlocked yes)
			(layer "Cmts.User")
			(hide yes)
			(effects
				(font
					(size 0.7874 0.5842)
					(thickness 0.1524)
				)
			)
		)
		(duplicate_pad_numbers_are_jumpers no)
		(fp_line
			(start 1.143 0.5588)
			(end 1.143 -0.5588)
			(stroke
				(width 0.1)
				(type default)
			)
			(layer "F.SilkS")
		)
		(fp_line
			(start 1.143 -0.5588)
			(end -1.143 -0.5588)
			(stroke
				(width 0.1)
				(type default)
			)
			(layer "F.SilkS")
		)
		(fp_line
			(start -1.143 0.5588)
			(end 1.143 0.5588)
			(stroke
				(width 0.1)
				(type default)
			)
			(layer "F.SilkS")
		)
		(fp_line
			(start -1.143 -0.5588)
			(end -1.143 0.5588)
			(stroke
				(width 0.1)
				(type default)
			)
			(layer "F.SilkS")
		)
		(fp_poly
			(pts
				(xy -1.143 0.5588) (xy 1.143 0.5588) (xy 1.143 -0.5588) (xy -1.143 -0.5588)
			)
			(stroke
				(width 0)
				(type default)
			)
			(fill no)
			(layer "F.CrtYd")
		)
		(fp_line
			(start 0.508 0.3048)
			(end 0.508 -0.3048)
			(stroke
				(width 0.1)
				(type default)
			)
			(layer "F.Fab")
		)
		(fp_line
			(start 0.508 -0.3048)
			(end -0.508 -0.3048)
			(stroke
				(width 0.1)
				(type default)
			)
			(layer "F.Fab")
		)
		(fp_line
			(start -0.508 0.3048)
			(end 0.508 0.3048)
			(stroke
				(width 0.1)
				(type default)
			)
			(layer "F.Fab")
		)
		(fp_line
			(start -0.508 -0.3048)
			(end -0.508 0.3048)
			(stroke
				(width 0.1)
				(type default)
			)
			(layer "F.Fab")
		)
		(pad "1" smd rect
			(at -0.5334 0 180)
			(size 0.7112 0.6096)
			(layers "F.Cu" "F.Mask" "F.Paste")
			(net "FPGA_OUT_SMA4_LED_GREEN_N")
		)
		(pad "2" smd rect
			(at 0.5334 0 180)
			(size 0.7112 0.6096)
			(layers "F.Cu" "F.Mask" "F.Paste")
			(net "UNNAMED_14_LED4PV14_I268_4")
		)
		(zone
			(layer "F.Cu")
			(hatch none 0.5)
			(connect_pads
				(clearance 0)
			)
			(min_thickness 0.25)
			(keepout
				(tracks allowed)
				(vias not_allowed)
				(pads allowed)
				(copperpour not_allowed)
				(footprints allowed)
			)
			(placement
				(enabled no)
				(sheetname "")
			)
			(fill
				(thermal_gap 0.5)
				(thermal_bridge_width 0.5)
				(island_removal_mode 0)
			)
			(polygon
				(pts
					(xy 19.544538 -50.4698) (xy 19.392138 -50.4698) (xy 19.392138 -49.8602) (xy 19.544538 -49.8602)
				)
			)
		)
		(zone
			(layer "F.Cu")
			(hatch none 0.5)
			(connect_pads
				(clearance 0)
			)
			(min_thickness 0.25)
			(keepout
				(tracks not_allowed)
				(vias allowed)
				(pads allowed)
				(copperpour not_allowed)
				(footprints allowed)
			)
			(placement
				(enabled no)
				(sheetname "")
			)
			(fill
				(thermal_gap 0.5)
				(thermal_bridge_width 0.5)
				(island_removal_mode 0)
			)
			(polygon
				(pts
					(xy 19.544538 -50.4698) (xy 19.392138 -50.4698) (xy 19.392138 -49.8602) (xy 19.544538 -49.8602)
				)
			)
		)
	)
	(footprint ""
		(layer "F.Cu")
		(at 23.507192 -66.8528 180)
		(property "Reference" "L18"
			(at -3.035808 0.03683 0)
			(unlocked yes)
			(layer "F.SilkS")
			(effects
				(font
					(size 0.7874 0.5842)
					(thickness 0.1524)
				)
			)
		)
		(property "Value" "VAL*"
			(at 0.014732 2.526538 180)
			(unlocked yes)
			(layer "F.Fab")
			(hide yes)
			(effects
				(font
					(size 0.7874 0.5842)
					(thickness 0.000001)
				)
			)
		)
		(property "Tolerance" "TOL*"
			(at 0.014732 3.503676 180)
			(unlocked yes)
			(layer "Cmts.User")
			(hide yes)
			(effects
				(font
					(size 0.7874 0.5842)
					(thickness 0.000001)
				)
			)
		)
		(property "User Part Number" "PARTNUM*"
			(at 0.02794 4.480814 180)
			(unlocked yes)
			(layer "Cmts.User")
			(hide yes)
			(effects
				(font
					(size 0.7874 0.5842)
					(thickness 0.000001)
				)
			)
		)
		(property "Device Type" "FERRITEBEAD-G191-10097-01,600OA"
			(at 0.014732 1.600708 180)
			(unlocked yes)
			(layer "F.Fab")
			(hide yes)
			(effects
				(font
					(size 0.7874 0.5842)
					(thickness 0.000001)
				)
			)
		)
		(duplicate_pad_numbers_are_jumpers no)
		(fp_line
			(start 1.3208 0.7112)
			(end -1.3208 0.7112)
			(stroke
				(width 0.1)
				(type default)
			)
			(layer "F.SilkS")
		)
		(fp_line
			(start 1.3208 -0.7112)
			(end 1.3208 0.7112)
			(stroke
				(width 0.1)
				(type default)
			)
			(layer "F.SilkS")
		)
		(fp_line
			(start -1.3208 0.7112)
			(end -1.3208 -0.7112)
			(stroke
				(width 0.1)
				(type default)
			)
			(layer "F.SilkS")
		)
		(fp_line
			(start -1.3208 -0.7112)
			(end 1.3208 -0.7112)
			(stroke
				(width 0.1)
				(type default)
			)
			(layer "F.SilkS")
		)
		(fp_rect
			(start -1.3208 0.7112)
			(end 1.3208 -0.7112)
			(stroke
				(width 0)
				(type default)
			)
			(fill no)
			(layer "F.CrtYd")
		)
		(fp_line
			(start 0.8128 0.4572)
			(end -0.8128 0.4572)
			(stroke
				(width 0.1)
				(type default)
			)
			(layer "F.Fab")
		)
		(fp_line
			(start 0.8128 -0.4572)
			(end 0.8128 0.4572)
			(stroke
				(width 0.1)
				(type default)
			)
			(layer "F.Fab")
		)
		(fp_line
			(start -0.8128 0.4572)
			(end -0.8128 -0.4572)
			(stroke
				(width 0.1)
				(type default)
			)
			(layer "F.Fab")
		)
		(fp_line
			(start -0.8128 -0.4572)
			(end 0.8128 -0.4572)
			(stroke
				(width 0.1)
				(type default)
			)
			(layer "F.Fab")
		)
		(pad "1" smd rect
			(at -0.6858 0 180)
			(size 0.762 0.8636)
			(layers "F.Cu" "F.Mask" "F.Paste")
			(net "XP1R8V_FPGA")
		)
		(pad "2" smd rect
			(at 0.6858 0 180)
			(size 0.762 0.8636)
			(layers "F.Cu" "F.Mask" "F.Paste")
			(net "XP1R8V_ICP10100")
		)
		(zone
			(layer "F.Cu")
			(hatch none 0.5)
			(connect_pads
				(clearance 0)
			)
			(min_thickness 0.25)
			(keepout
				(tracks not_allowed)
				(vias allowed)
				(pads allowed)
				(copperpour not_allowed)
				(footprints allowed)
			)
			(placement
				(enabled no)
				(sheetname "")
			)
			(fill
				(thermal_gap 0.5)
				(thermal_bridge_width 0.5)
				(island_removal_mode 0)
			)
			(polygon
				(pts
					(xy 23.659592 -67.31) (xy 23.354792 -67.31) (xy 23.354792 -66.3956) (xy 23.659592 -66.3956)
				)
			)
		)
		(zone
			(layer "F.Cu")
			(hatch none 0.5)
			(connect_pads
				(clearance 0)
			)
			(min_thickness 0.25)
			(keepout
				(tracks allowed)
				(vias not_allowed)
				(pads allowed)
				(copperpour not_allowed)
				(footprints allowed)
			)
			(placement
				(enabled no)
				(sheetname "")
			)
			(fill
				(thermal_gap 0.5)
				(thermal_bridge_width 0.5)
				(island_removal_mode 0)
			)
			(polygon
				(pts
					(xy 23.659592 -67.31) (xy 23.354792 -67.31) (xy 23.354792 -66.3956) (xy 23.659592 -66.3956)
				)
			)
		)
	)
	(footprint ""
		(layer "F.Cu")
		(at 56.134 -132.715)
		(property "Reference" "SP41"
			(at 0 0 0)
			(layer "F.SilkS")
			(hide yes)
			(effects
				(font
					(size 1.27 1.27)
				)
			)
		)
		(property "Value" ""
			(at 0 0 0)
			(layer "F.Fab")
			(effects
				(font
					(size 1.27 1.27)
				)
			)
		)
		(duplicate_pad_numbers_are_jumpers no)
	)
)
